# S9S_MB_2U (Grand Teton) — schematic netlist excerpt (pin names and nets, part order shuffled) for the footprints in the layout excerpt that follows; sources: Cadence DE-HDL packaged netlist, KiCad conversion of 03242023_DA0F0TMBIJ0_F0T_Motherboard_J_brd_V01_OCP.brd

R1996  Q_RES  33.2 1% CHIP  pkg 0402LF  page 223 : A = FM_PCH_SLP_S4_N ; B = FM_SLPS4_PLD_N
PC258_P0_6  Q_CAP  22UF 16V 20% X6S  pkg C0805  page 269 : A = SW_P12V_PVCCIN_CPU0_FLT ; B = GND
C1312  Q_CAP  1UF 25V 10% X6S  pkg C0402  page 210 : A = P3V3_AUX_CLK_GEN_VDDMXCK_CK440 ; B = GND

(kicad_pcb
	(version 20260206)
	(generator "pcbnew")
	(generator_version "10.0")
	(general
		(thickness 1.6)
		(legacy_teardrops no)
	)
	(paper "A4")
	(title_block
		(title "03242023_DA0F0TMBIJ0_F0T_Motherboard_J_brd_V01_OCP.brd")
		(comment 1 "Grand Teton / footprints 5773-5775 of 6105")
	)
	(layers
		(0 "F.Cu" signal "TOP")
		(4 "In1.Cu" signal "GND")
		(6 "In2.Cu" signal "IN1")
		(8 "In3.Cu" signal "GND1")
		(10 "In4.Cu" signal "IN2")
		(12 "In5.Cu" signal "GND2")
		(14 "In6.Cu" signal "IN3")
		(16 "In7.Cu" signal "GND3")
		(18 "In8.Cu" signal "VCC")
		(20 "In9.Cu" signal "VCC1")
		(22 "In10.Cu" signal "GND4")
		(24 "In11.Cu" signal "IN4")
		(26 "In12.Cu" signal "GND5")
		(28 "In13.Cu" signal "IN5")
		(30 "In14.Cu" signal "GND6")
		(32 "In15.Cu" signal "IN6")
		(34 "In16.Cu" signal "GND7")
		(2 "B.Cu" signal "BOTTOM")
		(9 "F.Adhes" user "F.Adhesive")
		(11 "B.Adhes" user "B.Adhesive")
		(13 "F.Paste" user "Package Geometry/Pastemask Top")
		(15 "B.Paste" user "Package Geometry/Pastemask Bottom")
		(5 "F.SilkS" user "Ref Des/Silkscreen Top")
		(7 "B.SilkS" user "Ref Des/Silkscreen Bottom")
		(1 "F.Mask" user "Board Geometry/Soldermask Top")
		(3 "B.Mask" user "Board Geometry/Soldermask Bottom")
		(17 "Dwgs.User" user "User.Drawings")
		(19 "Cmts.User" user "User.Comments")
		(21 "Eco1.User" user "User.Eco1")
		(23 "Eco2.User" user "User.Eco2")
		(25 "Edge.Cuts" user "Board Geometry/Outline")
		(27 "Margin" user)
		(31 "F.CrtYd" user "Package Geometry/Place Bound Top")
		(29 "B.CrtYd" user "Package Geometry/Place Bound Bottom")
		(35 "F.Fab" user "Ref Des/Assembly Top")
		(33 "B.Fab" user "Ref Des/Assembly Bottom")
	)
	(footprint ""
		(layer "B.Cu")
		(at 255.064006 -102.285292 90)
		(property "Reference" "C1312"
			(at 0 0 90)
			(layer "B.SilkS")
			(hide yes)
			(effects
				(font
					(size 1.27 1.27)
				)
				(justify mirror)
			)
		)
		(property "Value" ""
			(at 0 0 90)
			(layer "B.Fab")
			(effects
				(font
					(size 1.27 1.27)
				)
				(justify mirror)
			)
		)
		(duplicate_pad_numbers_are_jumpers no)
		(fp_line
			(start 0.7874 -0.4064)
			(end -0.7874 -0.4064)
			(stroke
				(width 0.1524)
				(type default)
			)
			(layer "B.SilkS")
		)
		(fp_line
			(start -0.7874 -0.4064)
			(end -0.7874 0.4064)
			(stroke
				(width 0.1524)
				(type default)
			)
			(layer "B.SilkS")
		)
		(fp_line
			(start 0.7874 0.4064)
			(end 0.7874 -0.4064)
			(stroke
				(width 0.1524)
				(type default)
			)
			(layer "B.SilkS")
		)
		(fp_line
			(start -0.7874 0.4064)
			(end 0.7874 0.4064)
			(stroke
				(width 0.1524)
				(type default)
			)
			(layer "B.SilkS")
		)
		(fp_line
			(start 0.67945 -0.305054)
			(end 0.12065 -0.305054)
			(stroke
				(width 0.1)
				(type default)
			)
			(layer "B.Fab")
		)
		(fp_line
			(start 0.12065 -0.305054)
			(end 0.12065 -0.2794)
			(stroke
				(width 0.1)
				(type default)
			)
			(layer "B.Fab")
		)
		(fp_line
			(start -0.12065 -0.3048)
			(end -0.67945 -0.3048)
			(stroke
				(width 0.1)
				(type default)
			)
			(layer "B.Fab")
		)
		(fp_line
			(start -0.67945 -0.3048)
			(end -0.67945 0.3048)
			(stroke
				(width 0.1)
				(type default)
			)
			(layer "B.Fab")
		)
		(fp_line
			(start 0.12065 -0.2794)
			(end -0.12065 -0.2794)
			(stroke
				(width 0.1)
				(type default)
			)
			(layer "B.Fab")
		)
		(fp_line
			(start -0.12065 -0.2794)
			(end -0.12065 -0.3048)
			(stroke
				(width 0.1)
				(type default)
			)
			(layer "B.Fab")
		)
		(fp_line
			(start 0.12065 0.2794)
			(end 0.12065 0.3048)
			(stroke
				(width 0.1)
				(type default)
			)
			(layer "B.Fab")
		)
		(fp_line
			(start -0.120396 0.2794)
			(end 0.12065 0.2794)
			(stroke
				(width 0.1)
				(type default)
			)
			(layer "B.Fab")
		)
		(fp_line
			(start 0.67945 0.3048)
			(end 0.67945 -0.305054)
			(stroke
				(width 0.1)
				(type default)
			)
			(layer "B.Fab")
		)
		(fp_line
			(start 0.12065 0.3048)
			(end 0.67945 0.3048)
			(stroke
				(width 0.1)
				(type default)
			)
			(layer "B.Fab")
		)
		(fp_line
			(start -0.120396 0.3048)
			(end -0.120396 0.2794)
			(stroke
				(width 0.1)
				(type default)
			)
			(layer "B.Fab")
		)
		(fp_line
			(start -0.67945 0.3048)
			(end -0.120396 0.3048)
			(stroke
				(width 0.1)
				(type default)
			)
			(layer "B.Fab")
		)
		(pad "1" smd circle
			(at 0.40005 0 270)
			(size 0 0)
			(layers "B.Cu" "B.Mask" "B.Paste")
			(net "P3V3_AUX_CLK_GEN_VDDMXCK_CK440")
		)
		(pad "2" smd circle
			(at -0.40005 0 270)
			(size 0 0)
			(layers "B.Cu" "B.Mask" "B.Paste")
			(net "GND")
		)
	)
	(footprint ""
		(layer "B.Cu")
		(at 324.19163 -25.68702 90)
		(property "Reference" "R1996"
			(at 0 0 90)
			(layer "B.SilkS")
			(hide yes)
			(effects
				(font
					(size 1.27 1.27)
				)
				(justify mirror)
			)
		)
		(property "Value" ""
			(at 0 0 90)
			(layer "B.Fab")
			(effects
				(font
					(size 1.27 1.27)
				)
				(justify mirror)
			)
		)
		(duplicate_pad_numbers_are_jumpers no)
		(fp_line
			(start 0.7874 -0.4064)
			(end -0.7874 -0.4064)
			(stroke
				(width 0.1524)
				(type default)
			)
			(layer "B.SilkS")
		)
		(fp_line
			(start -0.7874 -0.4064)
			(end -0.7874 0.4064)
			(stroke
				(width 0.1524)
				(type default)
			)
			(layer "B.SilkS")
		)
		(fp_line
			(start 0.7874 0.4064)
			(end 0.7874 -0.4064)
			(stroke
				(width 0.1524)
				(type default)
			)
			(layer "B.SilkS")
		)
		(fp_line
			(start -0.7874 0.4064)
			(end 0.7874 0.4064)
			(stroke
				(width 0.1524)
				(type default)
			)
			(layer "B.SilkS")
		)
		(fp_line
			(start 0.67945 -0.305054)
			(end 0.12065 -0.305054)
			(stroke
				(width 0.1)
				(type default)
			)
			(layer "B.Fab")
		)
		(fp_line
			(start 0.12065 -0.305054)
			(end 0.12065 -0.2794)
			(stroke
				(width 0.1)
				(type default)
			)
			(layer "B.Fab")
		)
		(fp_line
			(start -0.12065 -0.3048)
			(end -0.67945 -0.3048)
			(stroke
				(width 0.1)
				(type default)
			)
			(layer "B.Fab")
		)
		(fp_line
			(start -0.67945 -0.3048)
			(end -0.67945 0.3048)
			(stroke
				(width 0.1)
				(type default)
			)
			(layer "B.Fab")
		)
		(fp_line
			(start 0.12065 -0.2794)
			(end -0.12065 -0.2794)
			(stroke
				(width 0.1)
				(type default)
			)
			(layer "B.Fab")
		)
		(fp_line
			(start -0.12065 -0.2794)
			(end -0.12065 -0.3048)
			(stroke
				(width 0.1)
				(type default)
			)
			(layer "B.Fab")
		)
		(fp_line
			(start 0.12065 0.2794)
			(end 0.12065 0.3048)
			(stroke
				(width 0.1)
				(type default)
			)
			(layer "B.Fab")
		)
		(fp_line
			(start -0.120396 0.2794)
			(end 0.12065 0.2794)
			(stroke
				(width 0.1)
				(type default)
			)
			(layer "B.Fab")
		)
		(fp_line
			(start 0.67945 0.3048)
			(end 0.67945 -0.305054)
			(stroke
				(width 0.1)
				(type default)
			)
			(layer "B.Fab")
		)
		(fp_line
			(start 0.12065 0.3048)
			(end 0.67945 0.3048)
			(stroke
				(width 0.1)
				(type default)
			)
			(layer "B.Fab")
		)
		(fp_line
			(start -0.120396 0.3048)
			(end -0.120396 0.2794)
			(stroke
				(width 0.1)
				(type default)
			)
			(layer "B.Fab")
		)
		(fp_line
			(start -0.67945 0.3048)
			(end -0.120396 0.3048)
			(stroke
				(width 0.1)
				(type default)
			)
			(layer "B.Fab")
		)
		(pad "1" smd circle
			(at 0.40005 0 270)
			(size 0 0)
			(layers "B.Cu" "B.Mask" "B.Paste")
			(net "FM_PCH_SLP_S4_N")
		)
		(pad "2" smd circle
			(at -0.40005 0 270)
			(size 0 0)
			(layers "B.Cu" "B.Mask" "B.Paste")
			(net "FM_SLPS4_PLD_N")
		)
	)
	(footprint ""
		(layer "B.Cu")
		(at 338.280502 -341.017606 -90)
		(property "Reference" "PC258_P0_6"
			(at 0 0 90)
			(layer "B.SilkS")
			(hide yes)
			(effects
				(font
					(size 1.27 1.27)
				)
				(justify mirror)
			)
		)
		(property "Value" ""
			(at 0 0 90)
			(layer "B.Fab")
			(effects
				(font
					(size 1.27 1.27)
				)
				(justify mirror)
			)
		)
		(duplicate_pad_numbers_are_jumpers no)
		(fp_line
			(start -1.524 0.762)
			(end 1.524 0.762)
			(stroke
				(width 0.1524)
				(type default)
			)
			(layer "B.SilkS")
		)
		(fp_line
			(start 1.524 0.762)
			(end 1.524 -0.762)
			(stroke
				(width 0.1524)
				(type default)
			)
			(layer "B.SilkS")
		)
		(fp_line
			(start -1.524 -0.762)
			(end -1.524 0.762)
			(stroke
				(width 0.1524)
				(type default)
			)
			(layer "B.SilkS")
		)
		(fp_line
			(start 1.524 -0.762)
			(end -1.524 -0.762)
			(stroke
				(width 0.1524)
				(type default)
			)
			(layer "B.SilkS")
		)
		(fp_line
			(start -1.1049 0.724916)
			(end -1.1049 -0.724916)
			(stroke
				(width 0.1)
				(type default)
			)
			(layer "B.Fab")
		)
		(fp_line
			(start 1.1049 0.724916)
			(end -1.1049 0.724916)
			(stroke
				(width 0.1)
				(type default)
			)
			(layer "B.Fab")
		)
		(fp_line
			(start -1.1049 -0.724916)
			(end 1.1049 -0.724916)
			(stroke
				(width 0.1)
				(type default)
			)
			(layer "B.Fab")
		)
		(fp_line
			(start 1.1049 -0.724916)
			(end 1.1049 0.724916)
			(stroke
				(width 0.1)
				(type default)
			)
			(layer "B.Fab")
		)
		(pad "1" smd rect
			(at 0.889 0 270)
			(size 1.016 1.27)
			(layers "B.Cu" "B.Mask" "B.Paste")
			(net "SW_P12V_PVCCIN_CPU0_FLT")
		)
		(pad "2" smd rect
			(at -0.889 0 270)
			(size 1.016 1.27)
			(layers "B.Cu" "B.Mask" "B.Paste")
			(net "GND")
		)
	)
)
